# TIMECARD (Time Appliance Project (Time Card)) — schematic netlist excerpt (pin names and nets, part order shuffled) for the footprints in the layout excerpt that follows; sources: Cadence DE-HDL packaged netlist, KiCad conversion of R4006-B0001-02_R01.brd

C122  CAPACITOR  0.1UF 10V 10%  pkg SMC_0402R_H022  page 14 : \1\ = XP2R5V_FPGA ; \2\ = SG
R282  RESISTOR  4.7KOHM 1%  pkg SMC_0402R_H016  page 19 : \1\ = XP3R3V_FPGA ; \2\ = ICP10100_I2C_SCL

(kicad_pcb
	(version 20260206)
	(generator "pcbnew")
	(generator_version "10.0")
	(general
		(thickness 1.6)
		(legacy_teardrops no)
	)
	(paper "A4")
	(title_block
		(title "timecard-production-celestica-r4006 — R4006-B0001-02_R01.brd")
		(comment 1 "Time Appliance Project (Time Card) / footprints 982-983 of 1113")
	)
	(layers
		(0 "F.Cu" signal "TOP")
		(4 "In1.Cu" signal "L02_GND1")
		(6 "In2.Cu" signal "L03_SIG1")
		(8 "In3.Cu" signal "L04_GND2")
		(10 "In4.Cu" signal "L05_VCC1")
		(12 "In5.Cu" signal "L06_VCC2")
		(14 "In6.Cu" signal "L07_GND3")
		(16 "In7.Cu" signal "L08_SIG2")
		(18 "In8.Cu" signal "L09_GND4")
		(2 "B.Cu" signal "BOTTOM")
		(9 "F.Adhes" user "F.Adhesive")
		(11 "B.Adhes" user "B.Adhesive")
		(13 "F.Paste" user "Package Geometry/Pastemask Top")
		(15 "B.Paste" user "Package Geometry/Pastemask Bottom")
		(5 "F.SilkS" user "Ref Des/Silkscreen Top")
		(7 "B.SilkS" user "Ref Des/Silkscreen Bottom")
		(1 "F.Mask" user "Board Geometry/Soldermask Top")
		(3 "B.Mask" user "Board Geometry/Soldermask Bottom")
		(17 "Dwgs.User" user "User.Drawings")
		(19 "Cmts.User" user "User.Comments")
		(21 "Eco1.User" user "User.Eco1")
		(23 "Eco2.User" user "User.Eco2")
		(25 "Edge.Cuts" user "Board Geometry/Outline")
		(27 "Margin" user)
		(31 "F.CrtYd" user "Package Geometry/Place Bound Top")
		(29 "B.CrtYd" user "Package Geometry/Place Bound Bottom")
		(35 "F.Fab" user "Ref Des/Assembly Top")
		(33 "B.Fab" user "Ref Des/Assembly Bottom")
	)
	(footprint ""
		(layer "B.Cu")
		(at 18.161 -61.5442 -90)
		(property "Reference" "R282"
			(at 0.381 3.72237 270)
			(unlocked yes)
			(layer "B.SilkS")
			(effects
				(font
					(size 0.7874 0.5842)
					(thickness 0.1524)
				)
				(justify mirror)
			)
		)
		(property "Value" "VAL*"
			(at -0.02032 2.13233 270)
			(unlocked yes)
			(layer "B.Fab")
			(hide yes)
			(effects
				(font
					(size 0.7874 0.5842)
					(thickness 0.1524)
				)
				(justify mirror)
			)
		)
		(property "Tolerance" "TOL*"
			(at -0.044704 3.05435 270)
			(unlocked yes)
			(layer "Cmts.User")
			(hide yes)
			(effects
				(font
					(size 0.7874 0.5842)
					(thickness 0.1524)
				)
				(justify mirror)
			)
		)
		(property "User Part Number" "PARTNUM*"
			(at -0.02032 4.024884 270)
			(unlocked yes)
			(layer "Cmts.User")
			(hide yes)
			(effects
				(font
					(size 0.7874 0.5842)
					(thickness 0.1524)
				)
				(justify mirror)
			)
		)
		(property "Device Type" "RESISTOR-G155-14701-01,4.7KOHMA"
			(at -0.008382 1.210564 270)
			(unlocked yes)
			(layer "B.Fab")
			(hide yes)
			(effects
				(font
					(size 0.7874 0.5842)
					(thickness 0.1524)
				)
				(justify mirror)
			)
		)
		(duplicate_pad_numbers_are_jumpers no)
		(fp_line
			(start -1.143 0.5588)
			(end -1.143 -0.5588)
			(stroke
				(width 0.1)
				(type default)
			)
			(layer "B.SilkS")
		)
		(fp_line
			(start 1.143 0.5588)
			(end -1.143 0.5588)
			(stroke
				(width 0.1)
				(type default)
			)
			(layer "B.SilkS")
		)
		(fp_line
			(start -1.143 -0.5588)
			(end 1.143 -0.5588)
			(stroke
				(width 0.1)
				(type default)
			)
			(layer "B.SilkS")
		)
		(fp_line
			(start 1.143 -0.5588)
			(end 1.143 0.5588)
			(stroke
				(width 0.1)
				(type default)
			)
			(layer "B.SilkS")
		)
		(fp_poly
			(pts
				(xy 1.143 0.5588) (xy -1.143 0.5588) (xy -1.143 -0.5588) (xy 1.143 -0.5588)
			)
			(stroke
				(width 0)
				(type default)
			)
			(fill no)
			(layer "B.CrtYd")
		)
		(fp_line
			(start -0.508 0.3048)
			(end -0.508 -0.3048)
			(stroke
				(width 0.1)
				(type default)
			)
			(layer "B.Fab")
		)
		(fp_line
			(start 0.508 0.3048)
			(end -0.508 0.3048)
			(stroke
				(width 0.1)
				(type default)
			)
			(layer "B.Fab")
		)
		(fp_line
			(start -0.508 -0.3048)
			(end 0.508 -0.3048)
			(stroke
				(width 0.1)
				(type default)
			)
			(layer "B.Fab")
		)
		(fp_line
			(start 0.508 -0.3048)
			(end 0.508 0.3048)
			(stroke
				(width 0.1)
				(type default)
			)
			(layer "B.Fab")
		)
		(pad "1" smd rect
			(at 0.5334 0 90)
			(size 0.7112 0.6096)
			(layers "B.Cu" "B.Mask" "B.Paste")
			(net "XP3R3V_FPGA")
		)
		(pad "2" smd rect
			(at -0.5334 0 90)
			(size 0.7112 0.6096)
			(layers "B.Cu" "B.Mask" "B.Paste")
			(net "ICP10100_I2C_SCL")
		)
		(zone
			(layer "B.Cu")
			(hatch none 0.5)
			(connect_pads
				(clearance 0)
			)
			(min_thickness 0.25)
			(keepout
				(tracks allowed)
				(vias not_allowed)
				(pads allowed)
				(copperpour not_allowed)
				(footprints allowed)
			)
			(placement
				(enabled no)
				(sheetname "")
			)
			(fill
				(thermal_gap 0.5)
				(thermal_bridge_width 0.5)
				(island_removal_mode 0)
			)
			(polygon
				(pts
					(xy 17.8562 -61.468) (xy 18.4658 -61.468) (xy 18.4658 -61.6204) (xy 17.8562 -61.6204)
				)
			)
		)
		(zone
			(layer "B.Cu")
			(hatch none 0.5)
			(connect_pads
				(clearance 0)
			)
			(min_thickness 0.25)
			(keepout
				(tracks not_allowed)
				(vias allowed)
				(pads allowed)
				(copperpour not_allowed)
				(footprints allowed)
			)
			(placement
				(enabled no)
				(sheetname "")
			)
			(fill
				(thermal_gap 0.5)
				(thermal_bridge_width 0.5)
				(island_removal_mode 0)
			)
			(polygon
				(pts
					(xy 17.8562 -61.468) (xy 18.4658 -61.468) (xy 18.4658 -61.6204) (xy 17.8562 -61.6204)
				)
			)
		)
	)
	(footprint ""
		(layer "B.Cu")
		(at 121.073164 -35.772344 90)
		(property "Reference" "C122"
			(at 1.184656 1.069086 270)
			(unlocked yes)
			(layer "B.SilkS")
			(effects
				(font
					(size 0.635 0.4064)
					(thickness 0.1524)
				)
				(justify mirror)
			)
		)
		(property "Value" "VAL*"
			(at 0 3.718306 90)
			(unlocked yes)
			(layer "B.Fab")
			(hide yes)
			(effects
				(font
					(size 0.7874 0.5842)
					(thickness 0.127)
				)
				(justify mirror)
			)
		)
		(property "Tolerance" "TOL*"
			(at 0 4.861306 90)
			(unlocked yes)
			(layer "Cmts.User")
			(hide yes)
			(effects
				(font
					(size 0.7874 0.5842)
					(thickness 0.127)
				)
				(justify mirror)
			)
		)
		(property "User Part Number" "PARTNUM*"
			(at 0 2.575306 90)
			(unlocked yes)
			(layer "Cmts.User")
			(hide yes)
			(effects
				(font
					(size 0.7874 0.5842)
					(thickness 0.127)
				)
				(justify mirror)
			)
		)
		(property "Device Type" "CAPACITOR-G105-0B104-CK,0.1UF,A"
			(at 0 1.432306 90)
			(unlocked yes)
			(layer "B.Fab")
			(hide yes)
			(effects
				(font
					(size 0.7874 0.5842)
					(thickness 0.127)
				)
				(justify mirror)
			)
		)
		(duplicate_pad_numbers_are_jumpers no)
		(fp_line
			(start 0.970026 -0.4699)
			(end -0.970026 -0.4699)
			(stroke
				(width 0.1)
				(type default)
			)
			(layer "B.SilkS")
		)
		(fp_line
			(start -0.970026 -0.4699)
			(end -0.970026 0.4699)
			(stroke
				(width 0.1)
				(type default)
			)
			(layer "B.SilkS")
		)
		(fp_line
			(start 0.970026 0.4699)
			(end 0.970026 -0.4699)
			(stroke
				(width 0.1)
				(type default)
			)
			(layer "B.SilkS")
		)
		(fp_line
			(start -0.970026 0.4699)
			(end 0.970026 0.4699)
			(stroke
				(width 0.1)
				(type default)
			)
			(layer "B.SilkS")
		)
		(fp_poly
			(pts
				(xy 0.970026 0.4699) (xy -0.970026 0.4699) (xy -0.970026 -0.4699) (xy 0.970026 -0.4699)
			)
			(stroke
				(width 0)
				(type default)
			)
			(fill no)
			(layer "B.CrtYd")
		)
		(fp_line
			(start 0.508 -0.3048)
			(end -0.508 -0.3048)
			(stroke
				(width 0.1)
				(type default)
			)
			(layer "B.Fab")
		)
		(fp_line
			(start -0.508 -0.3048)
			(end -0.508 0.3048)
			(stroke
				(width 0.1)
				(type default)
			)
			(layer "B.Fab")
		)
		(fp_line
			(start 0.508 0.3048)
			(end 0.508 -0.3048)
			(stroke
				(width 0.1)
				(type default)
			)
			(layer "B.Fab")
		)
		(fp_line
			(start -0.508 0.3048)
			(end 0.508 0.3048)
			(stroke
				(width 0.1)
				(type default)
			)
			(layer "B.Fab")
		)
		(pad "1" smd circle
			(at 0.500126 0 270)
			(size 0.635 0.635)
			(layers "B.Cu" "B.Mask" "B.Paste")
			(net "XP2R5V_FPGA")
		)
		(pad "2" smd circle
			(at -0.500126 0 270)
			(size 0.635 0.635)
			(layers "B.Cu" "B.Mask" "B.Paste")
			(net "SG")
		)
	)
)
